(kicad_pcb
	(version 20260206)
	(generator "pcbnew")
	(generator_version "10.0")
	(general
		(thickness 1.6)
		(legacy_teardrops no)
	)
	(paper "A4")
	(title_block
		(title "03242023_DA0F0TMBIJ0_F0T_Motherboard_J_brd_V01_OCP.brd")
		(comment 1 "Grand Teton / footprints 6004-6009 of 6105")
	)
	(layers
		(0 "F.Cu" signal "TOP")
		(4 "In1.Cu" signal "GND")
		(6 "In2.Cu" signal "IN1")
		(8 "In3.Cu" signal "GND1")
		(10 "In4.Cu" signal "IN2")
		(12 "In5.Cu" signal "GND2")
		(14 "In6.Cu" signal "IN3")
		(16 "In7.Cu" signal "GND3")
		(18 "In8.Cu" signal "VCC")
		(20 "In9.Cu" signal "VCC1")
		(22 "In10.Cu" signal "GND4")
		(24 "In11.Cu" signal "IN4")
		(26 "In12.Cu" signal "GND5")
		(28 "In13.Cu" signal "IN5")
		(30 "In14.Cu" signal "GND6")
		(32 "In15.Cu" signal "IN6")
		(34 "In16.Cu" signal "GND7")
		(2 "B.Cu" signal "BOTTOM")
		(9 "F.Adhes" user "F.Adhesive")
		(11 "B.Adhes" user "B.Adhesive")
		(13 "F.Paste" user "Package Geometry/Pastemask Top")
		(15 "B.Paste" user "Package Geometry/Pastemask Bottom")
		(5 "F.SilkS" user "Ref Des/Silkscreen Top")
		(7 "B.SilkS" user "Ref Des/Silkscreen Bottom")
		(1 "F.Mask" user "Board Geometry/Soldermask Top")
		(3 "B.Mask" user "Board Geometry/Soldermask Bottom")
		(17 "Dwgs.User" user "User.Drawings")
		(19 "Cmts.User" user "User.Comments")
		(21 "Eco1.User" user "User.Eco1")
		(23 "Eco2.User" user "User.Eco2")
		(25 "Edge.Cuts" user "Board Geometry/Outline")
		(27 "Margin" user)
		(31 "F.CrtYd" user "Package Geometry/Place Bound Top")
		(29 "B.CrtYd" user "Package Geometry/Place Bound Bottom")
		(35 "F.Fab" user "Ref Des/Assembly Top")
		(33 "B.Fab" user "Ref Des/Assembly Bottom")
	)
	(footprint ""
		(layer "B.Cu")
		(at 325.688706 -74.871072 180)
		(property "Reference" "PJ63"
			(at -1.089914 1.737106 0)
			(unlocked yes)
			(layer "B.SilkS")
			(effects
				(font
					(size 0.7874 0.5842)
					(thickness 0.1524)
				)
				(justify left mirror)
			)
		)
		(property "Value" ""
			(at 0 0 0)
			(layer "B.Fab")
			(effects
				(font
					(size 1.27 1.27)
				)
				(justify mirror)
			)
		)
		(duplicate_pad_numbers_are_jumpers no)
		(pad "1" smd circle
			(at 0.7493 0 270)
			(size 0 0)
			(layers "B.Cu" "B.Mask" "B.Paste")
			(net "SH_P1V05_PCH_AUX_N")
		)
		(pad "2" smd rect
			(at -0.7493 0 90)
			(size 0.7112 0.8128)
			(layers "B.Cu" "B.Mask" "B.Paste")
			(net "GND")
		)
		(zone
			(layer "B.Cu")
			(hatch none 0.5)
			(connect_pads
				(clearance 0)
			)
			(min_thickness 0.25)
			(keepout
				(tracks allowed)
				(vias not_allowed)
				(pads allowed)
				(copperpour not_allowed)
				(footprints allowed)
			)
			(placement
				(enabled no)
				(sheetname "")
			)
			(fill
				(thermal_gap 0.5)
				(thermal_bridge_width 0.5)
				(island_removal_mode 0)
			)
			(polygon
				(pts
					(xy 324.507606 -75.282552) (xy 324.507606 -74.464926) (xy 326.895206 -74.464926) (xy 326.895206 -75.282552)
				)
			)
		)
	)
	(footprint ""
		(layer "B.Cu")
		(at 182.546752 -192.699894 -90)
		(property "Reference" "R327"
			(at 0 0 90)
			(layer "B.SilkS")
			(hide yes)
			(effects
				(font
					(size 1.27 1.27)
				)
				(justify mirror)
			)
		)
		(property "Value" ""
			(at 0 0 90)
			(layer "B.Fab")
			(effects
				(font
					(size 1.27 1.27)
				)
				(justify mirror)
			)
		)
		(duplicate_pad_numbers_are_jumpers no)
		(fp_line
			(start -0.7874 0.4064)
			(end 0.7874 0.4064)
			(stroke
				(width 0.1524)
				(type default)
			)
			(layer "B.SilkS")
		)
		(fp_line
			(start 0.7874 0.4064)
			(end 0.7874 -0.4064)
			(stroke
				(width 0.1524)
				(type default)
			)
			(layer "B.SilkS")
		)
		(fp_line
			(start -0.7874 -0.4064)
			(end -0.7874 0.4064)
			(stroke
				(width 0.1524)
				(type default)
			)
			(layer "B.SilkS")
		)
		(fp_line
			(start 0.7874 -0.4064)
			(end -0.7874 -0.4064)
			(stroke
				(width 0.1524)
				(type default)
			)
			(layer "B.SilkS")
		)
		(fp_line
			(start -0.67945 0.3048)
			(end -0.120396 0.3048)
			(stroke
				(width 0.1)
				(type default)
			)
			(layer "B.Fab")
		)
		(fp_line
			(start -0.120396 0.3048)
			(end -0.120396 0.2794)
			(stroke
				(width 0.1)
				(type default)
			)
			(layer "B.Fab")
		)
		(fp_line
			(start 0.12065 0.3048)
			(end 0.67945 0.3048)
			(stroke
				(width 0.1)
				(type default)
			)
			(layer "B.Fab")
		)
		(fp_line
			(start 0.67945 0.3048)
			(end 0.67945 -0.305054)
			(stroke
				(width 0.1)
				(type default)
			)
			(layer "B.Fab")
		)
		(fp_line
			(start -0.120396 0.2794)
			(end 0.12065 0.2794)
			(stroke
				(width 0.1)
				(type default)
			)
			(layer "B.Fab")
		)
		(fp_line
			(start 0.12065 0.2794)
			(end 0.12065 0.3048)
			(stroke
				(width 0.1)
				(type default)
			)
			(layer "B.Fab")
		)
		(fp_line
			(start -0.12065 -0.2794)
			(end -0.12065 -0.3048)
			(stroke
				(width 0.1)
				(type default)
			)
			(layer "B.Fab")
		)
		(fp_line
			(start 0.12065 -0.2794)
			(end -0.12065 -0.2794)
			(stroke
				(width 0.1)
				(type default)
			)
			(layer "B.Fab")
		)
		(fp_line
			(start -0.67945 -0.3048)
			(end -0.67945 0.3048)
			(stroke
				(width 0.1)
				(type default)
			)
			(layer "B.Fab")
		)
		(fp_line
			(start -0.12065 -0.3048)
			(end -0.67945 -0.3048)
			(stroke
				(width 0.1)
				(type default)
			)
			(layer "B.Fab")
		)
		(fp_line
			(start 0.12065 -0.305054)
			(end 0.12065 -0.2794)
			(stroke
				(width 0.1)
				(type default)
			)
			(layer "B.Fab")
		)
		(fp_line
			(start 0.67945 -0.305054)
			(end 0.12065 -0.305054)
			(stroke
				(width 0.1)
				(type default)
			)
			(layer "B.Fab")
		)
		(pad "1" smd circle
			(at 0.40005 0 90)
			(size 0 0)
			(layers "B.Cu" "B.Mask" "B.Paste")
			(net "P3V3_AUX")
		)
		(pad "2" smd circle
			(at -0.40005 0 90)
			(size 0 0)
			(layers "B.Cu" "B.Mask" "B.Paste")
			(net "FM_S3M_CPU1_CPLD_CONFIG_N")
		)
	)
	(footprint ""
		(layer "B.Cu")
		(at 35.567366 -192.924176 -90)
		(property "Reference" "R703"
			(at 0 0 90)
			(layer "B.SilkS")
			(hide yes)
			(effects
				(font
					(size 1.27 1.27)
				)
				(justify mirror)
			)
		)
		(property "Value" ""
			(at 0 0 90)
			(layer "B.Fab")
			(effects
				(font
					(size 1.27 1.27)
				)
				(justify mirror)
			)
		)
		(duplicate_pad_numbers_are_jumpers no)
		(fp_line
			(start -0.7874 0.4064)
			(end 0.7874 0.4064)
			(stroke
				(width 0.1524)
				(type default)
			)
			(layer "B.SilkS")
		)
		(fp_line
			(start 0.7874 0.4064)
			(end 0.7874 -0.4064)
			(stroke
				(width 0.1524)
				(type default)
			)
			(layer "B.SilkS")
		)
		(fp_line
			(start -0.7874 -0.4064)
			(end -0.7874 0.4064)
			(stroke
				(width 0.1524)
				(type default)
			)
			(layer "B.SilkS")
		)
		(fp_line
			(start 0.7874 -0.4064)
			(end -0.7874 -0.4064)
			(stroke
				(width 0.1524)
				(type default)
			)
			(layer "B.SilkS")
		)
		(fp_line
			(start -0.67945 0.3048)
			(end -0.120396 0.3048)
			(stroke
				(width 0.1)
				(type default)
			)
			(layer "B.Fab")
		)
		(fp_line
			(start -0.120396 0.3048)
			(end -0.120396 0.2794)
			(stroke
				(width 0.1)
				(type default)
			)
			(layer "B.Fab")
		)
		(fp_line
			(start 0.12065 0.3048)
			(end 0.67945 0.3048)
			(stroke
				(width 0.1)
				(type default)
			)
			(layer "B.Fab")
		)
		(fp_line
			(start 0.67945 0.3048)
			(end 0.67945 -0.305054)
			(stroke
				(width 0.1)
				(type default)
			)
			(layer "B.Fab")
		)
		(fp_line
			(start -0.120396 0.2794)
			(end 0.12065 0.2794)
			(stroke
				(width 0.1)
				(type default)
			)
			(layer "B.Fab")
		)
		(fp_line
			(start 0.12065 0.2794)
			(end 0.12065 0.3048)
			(stroke
				(width 0.1)
				(type default)
			)
			(layer "B.Fab")
		)
		(fp_line
			(start -0.12065 -0.2794)
			(end -0.12065 -0.3048)
			(stroke
				(width 0.1)
				(type default)
			)
			(layer "B.Fab")
		)
		(fp_line
			(start 0.12065 -0.2794)
			(end -0.12065 -0.2794)
			(stroke
				(width 0.1)
				(type default)
			)
			(layer "B.Fab")
		)
		(fp_line
			(start -0.67945 -0.3048)
			(end -0.67945 0.3048)
			(stroke
				(width 0.1)
				(type default)
			)
			(layer "B.Fab")
		)
		(fp_line
			(start -0.12065 -0.3048)
			(end -0.67945 -0.3048)
			(stroke
				(width 0.1)
				(type default)
			)
			(layer "B.Fab")
		)
		(fp_line
			(start 0.12065 -0.305054)
			(end 0.12065 -0.2794)
			(stroke
				(width 0.1)
				(type default)
			)
			(layer "B.Fab")
		)
		(fp_line
			(start 0.67945 -0.305054)
			(end 0.12065 -0.305054)
			(stroke
				(width 0.1)
				(type default)
			)
			(layer "B.Fab")
		)
		(pad "1" smd circle
			(at 0.40005 0 90)
			(size 0 0)
			(layers "B.Cu" "B.Mask" "B.Paste")
			(net "RST_PLD_CPU1_DRAM_AB_N")
		)
		(pad "2" smd circle
			(at -0.40005 0 90)
			(size 0 0)
			(layers "B.Cu" "B.Mask" "B.Paste")
			(net "GND")
		)
	)
	(footprint ""
		(layer "B.Cu")
		(at 181.464458 -317.26505 90)
		(property "Reference" "R3901"
			(at 0 0 90)
			(layer "B.SilkS")
			(hide yes)
			(effects
				(font
					(size 1.27 1.27)
				)
				(justify mirror)
			)
		)
		(property "Value" ""
			(at 0 0 90)
			(layer "B.Fab")
			(effects
				(font
					(size 1.27 1.27)
				)
				(justify mirror)
			)
		)
		(duplicate_pad_numbers_are_jumpers no)
		(fp_line
			(start 0.7874 -0.4064)
			(end -0.7874 -0.4064)
			(stroke
				(width 0.1524)
				(type default)
			)
			(layer "B.SilkS")
		)
		(fp_line
			(start -0.7874 -0.4064)
			(end -0.7874 0.4064)
			(stroke
				(width 0.1524)
				(type default)
			)
			(layer "B.SilkS")
		)
		(fp_line
			(start 0.7874 0.4064)
			(end 0.7874 -0.4064)
			(stroke
				(width 0.1524)
				(type default)
			)
			(layer "B.SilkS")
		)
		(fp_line
			(start -0.7874 0.4064)
			(end 0.7874 0.4064)
			(stroke
				(width 0.1524)
				(type default)
			)
			(layer "B.SilkS")
		)
		(fp_line
			(start 0.67945 -0.305054)
			(end 0.12065 -0.305054)
			(stroke
				(width 0.1)
				(type default)
			)
			(layer "B.Fab")
		)
		(fp_line
			(start 0.12065 -0.305054)
			(end 0.12065 -0.2794)
			(stroke
				(width 0.1)
				(type default)
			)
			(layer "B.Fab")
		)
		(fp_line
			(start -0.12065 -0.3048)
			(end -0.67945 -0.3048)
			(stroke
				(width 0.1)
				(type default)
			)
			(layer "B.Fab")
		)
		(fp_line
			(start -0.67945 -0.3048)
			(end -0.67945 0.3048)
			(stroke
				(width 0.1)
				(type default)
			)
			(layer "B.Fab")
		)
		(fp_line
			(start 0.12065 -0.2794)
			(end -0.12065 -0.2794)
			(stroke
				(width 0.1)
				(type default)
			)
			(layer "B.Fab")
		)
		(fp_line
			(start -0.12065 -0.2794)
			(end -0.12065 -0.3048)
			(stroke
				(width 0.1)
				(type default)
			)
			(layer "B.Fab")
		)
		(fp_line
			(start 0.12065 0.2794)
			(end 0.12065 0.3048)
			(stroke
				(width 0.1)
				(type default)
			)
			(layer "B.Fab")
		)
		(fp_line
			(start -0.120396 0.2794)
			(end 0.12065 0.2794)
			(stroke
				(width 0.1)
				(type default)
			)
			(layer "B.Fab")
		)
		(fp_line
			(start 0.67945 0.3048)
			(end 0.67945 -0.305054)
			(stroke
				(width 0.1)
				(type default)
			)
			(layer "B.Fab")
		)
		(fp_line
			(start 0.12065 0.3048)
			(end 0.67945 0.3048)
			(stroke
				(width 0.1)
				(type default)
			)
			(layer "B.Fab")
		)
		(fp_line
			(start -0.120396 0.3048)
			(end -0.120396 0.2794)
			(stroke
				(width 0.1)
				(type default)
			)
			(layer "B.Fab")
		)
		(fp_line
			(start -0.67945 0.3048)
			(end -0.120396 0.3048)
			(stroke
				(width 0.1)
				(type default)
			)
			(layer "B.Fab")
		)
		(pad "1" smd circle
			(at 0.40005 0 270)
			(size 0 0)
			(layers "B.Cu" "B.Mask" "B.Paste")
			(net "I3C_SPD_DDREFGH_CPU1_LVC1_SCL_2")
		)
		(pad "2" smd circle
			(at -0.40005 0 270)
			(size 0 0)
			(layers "B.Cu" "B.Mask" "B.Paste")
			(net "I3C_SPD_DDREFGH_CPU1_LVC1_SCL")
		)
	)
	(footprint ""
		(layer "B.Cu")
		(at 85.892894 -182.06466 -90)
		(property "Reference" "R757"
			(at 0 0 90)
			(layer "B.SilkS")
			(hide yes)
			(effects
				(font
					(size 1.27 1.27)
				)
				(justify mirror)
			)
		)
		(property "Value" ""
			(at 0 0 90)
			(layer "B.Fab")
			(effects
				(font
					(size 1.27 1.27)
				)
				(justify mirror)
			)
		)
		(duplicate_pad_numbers_are_jumpers no)
		(fp_line
			(start -0.7874 0.4064)
			(end 0.7874 0.4064)
			(stroke
				(width 0.1524)
				(type default)
			)
			(layer "B.SilkS")
		)
		(fp_line
			(start 0.7874 0.4064)
			(end 0.7874 -0.4064)
			(stroke
				(width 0.1524)
				(type default)
			)
			(layer "B.SilkS")
		)
		(fp_line
			(start -0.7874 -0.4064)
			(end -0.7874 0.4064)
			(stroke
				(width 0.1524)
				(type default)
			)
			(layer "B.SilkS")
		)
		(fp_line
			(start 0.7874 -0.4064)
			(end -0.7874 -0.4064)
			(stroke
				(width 0.1524)
				(type default)
			)
			(layer "B.SilkS")
		)
		(fp_line
			(start -0.67945 0.3048)
			(end -0.120396 0.3048)
			(stroke
				(width 0.1)
				(type default)
			)
			(layer "B.Fab")
		)
		(fp_line
			(start -0.120396 0.3048)
			(end -0.120396 0.2794)
			(stroke
				(width 0.1)
				(type default)
			)
			(layer "B.Fab")
		)
		(fp_line
			(start 0.12065 0.3048)
			(end 0.67945 0.3048)
			(stroke
				(width 0.1)
				(type default)
			)
			(layer "B.Fab")
		)
		(fp_line
			(start 0.67945 0.3048)
			(end 0.67945 -0.305054)
			(stroke
				(width 0.1)
				(type default)
			)
			(layer "B.Fab")
		)
		(fp_line
			(start -0.120396 0.2794)
			(end 0.12065 0.2794)
			(stroke
				(width 0.1)
				(type default)
			)
			(layer "B.Fab")
		)
		(fp_line
			(start 0.12065 0.2794)
			(end 0.12065 0.3048)
			(stroke
				(width 0.1)
				(type default)
			)
			(layer "B.Fab")
		)
		(fp_line
			(start -0.12065 -0.2794)
			(end -0.12065 -0.3048)
			(stroke
				(width 0.1)
				(type default)
			)
			(layer "B.Fab")
		)
		(fp_line
			(start 0.12065 -0.2794)
			(end -0.12065 -0.2794)
			(stroke
				(width 0.1)
				(type default)
			)
			(layer "B.Fab")
		)
		(fp_line
			(start -0.67945 -0.3048)
			(end -0.67945 0.3048)
			(stroke
				(width 0.1)
				(type default)
			)
			(layer "B.Fab")
		)
		(fp_line
			(start -0.12065 -0.3048)
			(end -0.67945 -0.3048)
			(stroke
				(width 0.1)
				(type default)
			)
			(layer "B.Fab")
		)
		(fp_line
			(start 0.12065 -0.305054)
			(end 0.12065 -0.2794)
			(stroke
				(width 0.1)
				(type default)
			)
			(layer "B.Fab")
		)
		(fp_line
			(start 0.67945 -0.305054)
			(end 0.12065 -0.305054)
			(stroke
				(width 0.1)
				(type default)
			)
			(layer "B.Fab")
		)
		(pad "1" smd circle
			(at 0.40005 0 90)
			(size 0 0)
			(layers "B.Cu" "B.Mask" "B.Paste")
			(net "PVNN_TERM_CPU0")
		)
		(pad "2" smd circle
			(at -0.40005 0 90)
			(size 0 0)
			(layers "B.Cu" "B.Mask" "B.Paste")
			(net "JTAG_DBP_CPU_QS_GTL_TMS")
		)
	)
	(footprint ""
		(layer "B.Cu")
		(at 193.71818 -423.669206 90)
		(property "Reference" "R4705"
			(at 0 0 90)
			(layer "B.SilkS")
			(hide yes)
			(effects
				(font
					(size 1.27 1.27)
				)
				(justify mirror)
			)
		)
		(property "Value" ""
			(at 0 0 90)
			(layer "B.Fab")
			(effects
				(font
					(size 1.27 1.27)
				)
				(justify mirror)
			)
		)
		(duplicate_pad_numbers_are_jumpers no)
		(fp_line
			(start 0.7874 -0.4064)
			(end -0.7874 -0.4064)
			(stroke
				(width 0.1524)
				(type default)
			)
			(layer "B.SilkS")
		)
		(fp_line
			(start -0.7874 -0.4064)
			(end -0.7874 0.4064)
			(stroke
				(width 0.1524)
				(type default)
			)
			(layer "B.SilkS")
		)
		(fp_line
			(start 0.7874 0.4064)
			(end 0.7874 -0.4064)
			(stroke
				(width 0.1524)
				(type default)
			)
			(layer "B.SilkS")
		)
		(fp_line
			(start -0.7874 0.4064)
			(end 0.7874 0.4064)
			(stroke
				(width 0.1524)
				(type default)
			)
			(layer "B.SilkS")
		)
		(fp_line
			(start 0.67945 -0.305054)
			(end 0.12065 -0.305054)
			(stroke
				(width 0.1)
				(type default)
			)
			(layer "B.Fab")
		)
		(fp_line
			(start 0.12065 -0.305054)
			(end 0.12065 -0.2794)
			(stroke
				(width 0.1)
				(type default)
			)
			(layer "B.Fab")
		)
		(fp_line
			(start -0.12065 -0.3048)
			(end -0.67945 -0.3048)
			(stroke
				(width 0.1)
				(type default)
			)
			(layer "B.Fab")
		)
		(fp_line
			(start -0.67945 -0.3048)
			(end -0.67945 0.3048)
			(stroke
				(width 0.1)
				(type default)
			)
			(layer "B.Fab")
		)
		(fp_line
			(start 0.12065 -0.2794)
			(end -0.12065 -0.2794)
			(stroke
				(width 0.1)
				(type default)
			)
			(layer "B.Fab")
		)
		(fp_line
			(start -0.12065 -0.2794)
			(end -0.12065 -0.3048)
			(stroke
				(width 0.1)
				(type default)
			)
			(layer "B.Fab")
		)
		(fp_line
			(start 0.12065 0.2794)
			(end 0.12065 0.3048)
			(stroke
				(width 0.1)
				(type default)
			)
			(layer "B.Fab")
		)
		(fp_line
			(start -0.120396 0.2794)
			(end 0.12065 0.2794)
			(stroke
				(width 0.1)
				(type default)
			)
			(layer "B.Fab")
		)
		(fp_line
			(start 0.67945 0.3048)
			(end 0.67945 -0.305054)
			(stroke
				(width 0.1)
				(type default)
			)
			(layer "B.Fab")
		)
		(fp_line
			(start 0.12065 0.3048)
			(end 0.67945 0.3048)
			(stroke
				(width 0.1)
				(type default)
			)
			(layer "B.Fab")
		)
		(fp_line
			(start -0.120396 0.3048)
			(end -0.120396 0.2794)
			(stroke
				(width 0.1)
				(type default)
			)
			(layer "B.Fab")
		)
		(fp_line
			(start -0.67945 0.3048)
			(end -0.120396 0.3048)
			(stroke
				(width 0.1)
				(type default)
			)
			(layer "B.Fab")
		)
		(pad "1" smd circle
			(at 0.40005 0 270)
			(size 0 0)
			(layers "B.Cu" "B.Mask" "B.Paste")
			(net "LED_P12V_PSU_R2")
		)
		(pad "2" smd circle
			(at -0.40005 0 270)
			(size 0 0)
			(layers "B.Cu" "B.Mask" "B.Paste")
			(net "LED_P12V_PSU_R3")
		)
	)
)
